# BASEBOARD_FAB2 (Tioga Pass) — schematic netlist excerpt (pin names and nets, part order shuffled) for the footprints in the layout excerpt that follows; sources: Cadence DE-HDL packaged netlist, KiCad conversion of Wiwynn_Tioga_Pass_MB.brd

L1A1  IND-120NH-30-GP  pkg DISCRET-GB2  page 227 : S = VR_PVDDQ_KLM_PH2_SW ; F = PVDDQ_KLM
C4E16  CAPP  270UF 16V 20% OSCON  pkg 2626  page 204 : A = VR_FET_SW_P12V_STBY_PVCCIN_CPU0 ; B = GND

(kicad_pcb
	(version 20260206)
	(generator "pcbnew")
	(generator_version "10.0")
	(general
		(thickness 1.6)
		(legacy_teardrops no)
	)
	(paper "A4")
	(title_block
		(title "Wiwynn_Tioga_Pass_MB.brd")
		(comment 1 "Tioga Pass / footprints 279-280 of 4770")
	)
	(layers
		(0 "F.Cu" signal "TOP")
		(4 "In1.Cu" signal "L2GND")
		(6 "In2.Cu" signal "L3")
		(8 "In3.Cu" signal "L4GND")
		(10 "In4.Cu" signal "L5")
		(12 "In5.Cu" signal "L6GND")
		(14 "In6.Cu" signal "L7VCC")
		(16 "In7.Cu" signal "L8VCC")
		(18 "In8.Cu" signal "L9GND")
		(20 "In9.Cu" signal "L10")
		(22 "In10.Cu" signal "L11GND")
		(24 "In11.Cu" signal "L12")
		(26 "In12.Cu" signal "L13GND")
		(2 "B.Cu" signal "BOTTOM")
		(9 "F.Adhes" user "F.Adhesive")
		(11 "B.Adhes" user "B.Adhesive")
		(13 "F.Paste" user "Package Geometry/Pastemask Top")
		(15 "B.Paste" user "Package Geometry/Pastemask Bottom")
		(5 "F.SilkS" user "Ref Des/Silkscreen Top")
		(7 "B.SilkS" user "Ref Des/Silkscreen Bottom")
		(1 "F.Mask" user "Board Geometry/Soldermask Top")
		(3 "B.Mask" user "Board Geometry/Soldermask Bottom")
		(17 "Dwgs.User" user "User.Drawings")
		(19 "Cmts.User" user "User.Comments")
		(21 "Eco1.User" user "User.Eco1")
		(23 "Eco2.User" user "User.Eco2")
		(25 "Edge.Cuts" user "Board Geometry/Outline")
		(27 "Margin" user)
		(31 "F.CrtYd" user "Package Geometry/Place Bound Top")
		(29 "B.CrtYd" user "Package Geometry/Place Bound Bottom")
		(35 "F.Fab" user "Ref Des/Assembly Top")
		(33 "B.Fab" user "Ref Des/Assembly Bottom")
	)
	(footprint ""
		(layer "F.Cu")
		(at 8.509 -147.32)
		(property "Reference" "L1A1"
			(at 3.378708 -4.251706 0)
			(unlocked yes)
			(layer "F.SilkS")
			(effects
				(font
					(size 0.4064 0.254)
					(thickness 0.1524)
				)
			)
		)
		(property "Value" ""
			(at 0 0 0)
			(layer "F.Fab")
			(effects
				(font
					(size 1.27 1.27)
				)
			)
		)
		(duplicate_pad_numbers_are_jumpers no)
		(fp_line
			(start -1.1303 -3.199892)
			(end 8.3693 -3.199892)
			(stroke
				(width 0.1524)
				(type default)
			)
			(layer "F.SilkS")
		)
		(fp_line
			(start -1.1303 -1.6637)
			(end -1.1303 -3.199892)
			(stroke
				(width 0.1524)
				(type default)
			)
			(layer "F.SilkS")
		)
		(fp_line
			(start -1.1303 3.199892)
			(end -1.1303 1.6637)
			(stroke
				(width 0.1524)
				(type default)
			)
			(layer "F.SilkS")
		)
		(fp_line
			(start 8.3693 -3.199892)
			(end 8.3693 -1.6637)
			(stroke
				(width 0.1524)
				(type default)
			)
			(layer "F.SilkS")
		)
		(fp_line
			(start 8.3693 1.6637)
			(end 8.3693 3.199892)
			(stroke
				(width 0.1524)
				(type default)
			)
			(layer "F.SilkS")
		)
		(fp_line
			(start 8.3693 3.199892)
			(end -1.1303 3.199892)
			(stroke
				(width 0.1524)
				(type default)
			)
			(layer "F.SilkS")
		)
		(fp_rect
			(start -1.1303 3.199892)
			(end 8.3693 -3.199892)
			(stroke
				(width 0)
				(type default)
			)
			(fill no)
			(layer "F.CrtYd")
		)
		(fp_line
			(start -1.1303 -3.199892)
			(end 8.3693 -3.199892)
			(stroke
				(width 0.1)
				(type default)
			)
			(layer "F.Fab")
		)
		(fp_line
			(start -1.1303 3.199892)
			(end -1.1303 -3.199892)
			(stroke
				(width 0.1)
				(type default)
			)
			(layer "F.Fab")
		)
		(fp_line
			(start 8.3693 -3.199892)
			(end 8.3693 3.199892)
			(stroke
				(width 0.1)
				(type default)
			)
			(layer "F.Fab")
		)
		(fp_line
			(start 8.3693 3.199892)
			(end -1.1303 3.199892)
			(stroke
				(width 0.1)
				(type default)
			)
			(layer "F.Fab")
		)
		(pad "1" smd rect
			(at 0 0)
			(size 3.683 2.667)
			(layers "F.Cu" "F.Mask" "F.Paste")
			(net "VR_PVDDQ_KLM_PH2_SW")
		)
		(pad "2" smd rect
			(at 7.239 0)
			(size 3.683 2.667)
			(layers "F.Cu" "F.Mask" "F.Paste")
			(net "PVDDQ_KLM")
		)
	)
	(footprint ""
		(layer "F.Cu")
		(at 189.484 -56.642)
		(property "Reference" "C4E16"
			(at -4.16433 4.064 90)
			(unlocked yes)
			(layer "F.SilkS")
			(effects
				(font
					(size 0.7874 0.5842)
					(thickness 0.1524)
				)
				(justify left)
			)
		)
		(property "Value" ""
			(at 0 0 0)
			(layer "F.Fab")
			(effects
				(font
					(size 1.27 1.27)
				)
			)
		)
		(duplicate_pad_numbers_are_jumpers no)
		(fp_line
			(start -3.400044 0.028956)
			(end -3.400044 6.06679)
			(stroke
				(width 0.1524)
				(type default)
			)
			(layer "F.SilkS")
		)
		(fp_line
			(start -3.400044 6.06679)
			(end -0.9017 6.06679)
			(stroke
				(width 0.1524)
				(type default)
			)
			(layer "F.SilkS")
		)
		(fp_line
			(start -2.638044 -0.733044)
			(end -3.400044 0.028956)
			(stroke
				(width 0.1524)
				(type default)
			)
			(layer "F.SilkS")
		)
		(fp_line
			(start -0.9017 -1.714246)
			(end -0.9017 1.587754)
			(stroke
				(width 0.1524)
				(type default)
			)
			(layer "F.SilkS")
		)
		(fp_line
			(start -0.9017 -0.733044)
			(end -2.638044 -0.733044)
			(stroke
				(width 0.1524)
				(type default)
			)
			(layer "F.SilkS")
		)
		(fp_line
			(start -0.9017 1.587754)
			(end -0.7239 1.587754)
			(stroke
				(width 0.1524)
				(type default)
			)
			(layer "F.SilkS")
		)
		(fp_line
			(start -0.7239 -1.714246)
			(end -0.9017 -1.714246)
			(stroke
				(width 0.1524)
				(type default)
			)
			(layer "F.SilkS")
		)
		(fp_line
			(start 0.7239 1.587754)
			(end 0.9017 1.587754)
			(stroke
				(width 0.1524)
				(type default)
			)
			(layer "F.SilkS")
		)
		(fp_line
			(start 0.9017 -1.714246)
			(end 0.7239 -1.714246)
			(stroke
				(width 0.1524)
				(type default)
			)
			(layer "F.SilkS")
		)
		(fp_line
			(start 0.9017 1.587754)
			(end 0.9017 -1.714246)
			(stroke
				(width 0.1524)
				(type default)
			)
			(layer "F.SilkS")
		)
		(fp_line
			(start 0.9017 6.06679)
			(end 3.400044 6.06679)
			(stroke
				(width 0.1524)
				(type default)
			)
			(layer "F.SilkS")
		)
		(fp_line
			(start 2.638044 -0.733044)
			(end 0.9017 -0.733044)
			(stroke
				(width 0.1524)
				(type default)
			)
			(layer "F.SilkS")
		)
		(fp_line
			(start 3.400044 0.028956)
			(end 2.638044 -0.733044)
			(stroke
				(width 0.1524)
				(type default)
			)
			(layer "F.SilkS")
		)
		(fp_line
			(start 3.400044 6.06679)
			(end 3.400044 0.028956)
			(stroke
				(width 0.1524)
				(type default)
			)
			(layer "F.SilkS")
		)
		(fp_poly
			(pts
				(xy -3.400044 6.06679) (xy 3.400044 6.06679) (xy 3.400044 0.028956) (xy 2.638044 -0.733044) (xy -2.638044 -0.733044)
				(xy -3.400044 0.028956)
			)
			(stroke
				(width 0)
				(type default)
			)
			(fill no)
			(layer "F.CrtYd")
		)
		(fp_line
			(start -3.400044 0.028956)
			(end -3.400044 6.06679)
			(stroke
				(width 0.1)
				(type default)
			)
			(layer "F.Fab")
		)
		(fp_line
			(start -3.400044 6.06679)
			(end 3.400044 6.06679)
			(stroke
				(width 0.1)
				(type default)
			)
			(layer "F.Fab")
		)
		(fp_line
			(start -2.638044 -0.733044)
			(end -3.400044 0.028956)
			(stroke
				(width 0.1)
				(type default)
			)
			(layer "F.Fab")
		)
		(fp_line
			(start 2.638044 -0.733044)
			(end -2.638044 -0.733044)
			(stroke
				(width 0.1)
				(type default)
			)
			(layer "F.Fab")
		)
		(fp_line
			(start 3.400044 0.028956)
			(end 2.638044 -0.733044)
			(stroke
				(width 0.1)
				(type default)
			)
			(layer "F.Fab")
		)
		(fp_line
			(start 3.400044 6.06679)
			(end 3.400044 0.028956)
			(stroke
				(width 0.1)
				(type default)
			)
			(layer "F.Fab")
		)
		(fp_circle
			(center 0 2.667)
			(end 3.400044 2.667)
			(stroke
				(width 0.1)
				(type default)
			)
			(fill no)
			(layer "F.Fab")
		)
		(pad "1" smd rect
			(at 0 0)
			(size 0.7874 3.429)
			(layers "F.Cu" "F.Mask" "F.Paste")
			(net "VR_FET_SW_P12V_STBY_PVCCIN_CPU0")
		)
		(pad "2" smd rect
			(at 0 5.334)
			(size 0.7874 3.429)
			(layers "F.Cu" "F.Mask" "F.Paste")
			(net "GND")
		)
	)
)
